# TIMECARD (Time Appliance Project (Time Card)) — schematic netlist excerpt (pin names and nets, part order shuffled) for the footprints in the layout excerpt that follows; sources: Cadence DE-HDL packaged netlist, KiCad conversion of R4006-B0001-02_R01.brd

R103  RESISTOR  1KOHM 1%  pkg SMC_0402R_H016  page 21 : \1\ = UNNAMED_527_RESISTOR_I201_2 ; \2\ = SG
R501  RESISTOR  4.7KOHM 1%  pkg SMC_0402R_H016  page 11 : \1\ = SG ; \2\ = ANT4_IN

(kicad_pcb
	(version 20260206)
	(generator "pcbnew")
	(generator_version "10.0")
	(general
		(thickness 1.6)
		(legacy_teardrops no)
	)
	(paper "A4")
	(title_block
		(title "timecard-production-celestica-r4006 — R4006-B0001-02_R01.brd")
		(comment 1 "Time Appliance Project (Time Card) / footprints 718-719 of 1113")
	)
	(layers
		(0 "F.Cu" signal "TOP")
		(4 "In1.Cu" signal "L02_GND1")
		(6 "In2.Cu" signal "L03_SIG1")
		(8 "In3.Cu" signal "L04_GND2")
		(10 "In4.Cu" signal "L05_VCC1")
		(12 "In5.Cu" signal "L06_VCC2")
		(14 "In6.Cu" signal "L07_GND3")
		(16 "In7.Cu" signal "L08_SIG2")
		(18 "In8.Cu" signal "L09_GND4")
		(2 "B.Cu" signal "BOTTOM")
		(9 "F.Adhes" user "F.Adhesive")
		(11 "B.Adhes" user "B.Adhesive")
		(13 "F.Paste" user "Package Geometry/Pastemask Top")
		(15 "B.Paste" user "Package Geometry/Pastemask Bottom")
		(5 "F.SilkS" user "Ref Des/Silkscreen Top")
		(7 "B.SilkS" user "Ref Des/Silkscreen Bottom")
		(1 "F.Mask" user "Board Geometry/Soldermask Top")
		(3 "B.Mask" user "Board Geometry/Soldermask Bottom")
		(17 "Dwgs.User" user "User.Drawings")
		(19 "Cmts.User" user "User.Comments")
		(21 "Eco1.User" user "User.Eco1")
		(23 "Eco2.User" user "User.Eco2")
		(25 "Edge.Cuts" user "Board Geometry/Outline")
		(27 "Margin" user)
		(31 "F.CrtYd" user "Package Geometry/Place Bound Top")
		(29 "B.CrtYd" user "Package Geometry/Place Bound Bottom")
		(35 "F.Fab" user "Ref Des/Assembly Top")
		(33 "B.Fab" user "Ref Des/Assembly Bottom")
	)
	(footprint ""
		(layer "B.Cu")
		(at 118.364 -44.577)
		(property "Reference" "R501"
			(at 2.286 0.92075 0)
			(unlocked yes)
			(layer "B.SilkS")
			(effects
				(font
					(size 0.635 0.4064)
					(thickness 0.1524)
				)
				(justify mirror)
			)
		)
		(property "Value" "VAL*"
			(at -0.02032 2.13233 0)
			(unlocked yes)
			(layer "B.Fab")
			(hide yes)
			(effects
				(font
					(size 0.7874 0.5842)
					(thickness 0.1524)
				)
				(justify mirror)
			)
		)
		(property "Tolerance" "TOL*"
			(at -0.044704 3.05435 0)
			(unlocked yes)
			(layer "Cmts.User")
			(hide yes)
			(effects
				(font
					(size 0.7874 0.5842)
					(thickness 0.1524)
				)
				(justify mirror)
			)
		)
		(property "User Part Number" "PARTNUM*"
			(at -0.02032 4.024884 0)
			(unlocked yes)
			(layer "Cmts.User")
			(hide yes)
			(effects
				(font
					(size 0.7874 0.5842)
					(thickness 0.1524)
				)
				(justify mirror)
			)
		)
		(property "Device Type" "RESISTOR-G155-14701-01,4.7KOHMA"
			(at -0.008382 1.210564 0)
			(unlocked yes)
			(layer "B.Fab")
			(hide yes)
			(effects
				(font
					(size 0.7874 0.5842)
					(thickness 0.1524)
				)
				(justify mirror)
			)
		)
		(duplicate_pad_numbers_are_jumpers no)
		(fp_line
			(start -1.143 -0.5588)
			(end 1.143 -0.5588)
			(stroke
				(width 0.1)
				(type default)
			)
			(layer "B.SilkS")
		)
		(fp_line
			(start -1.143 0.5588)
			(end -1.143 -0.5588)
			(stroke
				(width 0.1)
				(type default)
			)
			(layer "B.SilkS")
		)
		(fp_line
			(start 1.143 -0.5588)
			(end 1.143 0.5588)
			(stroke
				(width 0.1)
				(type default)
			)
			(layer "B.SilkS")
		)
		(fp_line
			(start 1.143 0.5588)
			(end -1.143 0.5588)
			(stroke
				(width 0.1)
				(type default)
			)
			(layer "B.SilkS")
		)
		(fp_poly
			(pts
				(xy 1.143 0.5588) (xy -1.143 0.5588) (xy -1.143 -0.5588) (xy 1.143 -0.5588)
			)
			(stroke
				(width 0)
				(type default)
			)
			(fill no)
			(layer "B.CrtYd")
		)
		(fp_line
			(start -0.508 -0.3048)
			(end 0.508 -0.3048)
			(stroke
				(width 0.1)
				(type default)
			)
			(layer "B.Fab")
		)
		(fp_line
			(start -0.508 0.3048)
			(end -0.508 -0.3048)
			(stroke
				(width 0.1)
				(type default)
			)
			(layer "B.Fab")
		)
		(fp_line
			(start 0.508 -0.3048)
			(end 0.508 0.3048)
			(stroke
				(width 0.1)
				(type default)
			)
			(layer "B.Fab")
		)
		(fp_line
			(start 0.508 0.3048)
			(end -0.508 0.3048)
			(stroke
				(width 0.1)
				(type default)
			)
			(layer "B.Fab")
		)
		(pad "1" smd rect
			(at 0.5334 0 180)
			(size 0.7112 0.6096)
			(layers "B.Cu" "B.Mask" "B.Paste")
			(net "SG")
		)
		(pad "2" smd rect
			(at -0.5334 0 180)
			(size 0.7112 0.6096)
			(layers "B.Cu" "B.Mask" "B.Paste")
			(net "ANT4_IN")
		)
		(zone
			(layer "B.Cu")
			(hatch none 0.5)
			(connect_pads
				(clearance 0)
			)
			(min_thickness 0.25)
			(keepout
				(tracks allowed)
				(vias not_allowed)
				(pads allowed)
				(copperpour not_allowed)
				(footprints allowed)
			)
			(placement
				(enabled no)
				(sheetname "")
			)
			(fill
				(thermal_gap 0.5)
				(thermal_bridge_width 0.5)
				(island_removal_mode 0)
			)
			(polygon
				(pts
					(xy 118.4402 -44.2722) (xy 118.4402 -44.8818) (xy 118.2878 -44.8818) (xy 118.2878 -44.2722)
				)
			)
		)
		(zone
			(layer "B.Cu")
			(hatch none 0.5)
			(connect_pads
				(clearance 0)
			)
			(min_thickness 0.25)
			(keepout
				(tracks not_allowed)
				(vias allowed)
				(pads allowed)
				(copperpour not_allowed)
				(footprints allowed)
			)
			(placement
				(enabled no)
				(sheetname "")
			)
			(fill
				(thermal_gap 0.5)
				(thermal_bridge_width 0.5)
				(island_removal_mode 0)
			)
			(polygon
				(pts
					(xy 118.4402 -44.2722) (xy 118.4402 -44.8818) (xy 118.2878 -44.8818) (xy 118.2878 -44.2722)
				)
			)
		)
	)
	(footprint ""
		(layer "B.Cu")
		(at 157.734 -50.513996 90)
		(property "Reference" "R103"
			(at -7.874 1.35763 270)
			(unlocked yes)
			(layer "B.SilkS")
			(effects
				(font
					(size 0.7874 0.5842)
					(thickness 0.1524)
				)
				(justify mirror)
			)
		)
		(property "Value" "VAL*"
			(at -0.02032 2.13233 90)
			(unlocked yes)
			(layer "B.Fab")
			(hide yes)
			(effects
				(font
					(size 0.7874 0.5842)
					(thickness 0.1524)
				)
				(justify mirror)
			)
		)
		(property "Device Type" "RESISTOR-G155-11001-01,1KOHM,1%"
			(at -0.008382 1.210564 90)
			(unlocked yes)
			(layer "B.Fab")
			(hide yes)
			(effects
				(font
					(size 0.7874 0.5842)
					(thickness 0.1524)
				)
				(justify mirror)
			)
		)
		(property "User Part Number" "PARTNUM*"
			(at -0.02032 4.024884 90)
			(unlocked yes)
			(layer "Cmts.User")
			(hide yes)
			(effects
				(font
					(size 0.7874 0.5842)
					(thickness 0.1524)
				)
				(justify mirror)
			)
		)
		(property "Tolerance" "TOL*"
			(at -0.044704 3.05435 90)
			(unlocked yes)
			(layer "Cmts.User")
			(hide yes)
			(effects
				(font
					(size 0.7874 0.5842)
					(thickness 0.1524)
				)
				(justify mirror)
			)
		)
		(duplicate_pad_numbers_are_jumpers no)
		(fp_line
			(start 1.143 -0.5588)
			(end 1.143 0.5588)
			(stroke
				(width 0.1)
				(type default)
			)
			(layer "B.SilkS")
		)
		(fp_line
			(start -1.143 -0.5588)
			(end 1.143 -0.5588)
			(stroke
				(width 0.1)
				(type default)
			)
			(layer "B.SilkS")
		)
		(fp_line
			(start 1.143 0.5588)
			(end -1.143 0.5588)
			(stroke
				(width 0.1)
				(type default)
			)
			(layer "B.SilkS")
		)
		(fp_line
			(start -1.143 0.5588)
			(end -1.143 -0.5588)
			(stroke
				(width 0.1)
				(type default)
			)
			(layer "B.SilkS")
		)
		(fp_rect
			(start 1.143 0.5588)
			(end -1.143 -0.5588)
			(stroke
				(width 0)
				(type default)
			)
			(fill no)
			(layer "B.CrtYd")
		)
		(fp_line
			(start 0.508 -0.3048)
			(end 0.508 0.3048)
			(stroke
				(width 0.1)
				(type default)
			)
			(layer "B.Fab")
		)
		(fp_line
			(start -0.508 -0.3048)
			(end 0.508 -0.3048)
			(stroke
				(width 0.1)
				(type default)
			)
			(layer "B.Fab")
		)
		(fp_line
			(start 0.508 0.3048)
			(end -0.508 0.3048)
			(stroke
				(width 0.1)
				(type default)
			)
			(layer "B.Fab")
		)
		(fp_line
			(start -0.508 0.3048)
			(end -0.508 -0.3048)
			(stroke
				(width 0.1)
				(type default)
			)
			(layer "B.Fab")
		)
		(pad "1" smd rect
			(at 0.5334 0 270)
			(size 0.7112 0.6096)
			(layers "B.Cu" "B.Mask" "B.Paste")
			(net "UNNAMED_527_RESISTOR_I201_2")
		)
		(pad "2" smd rect
			(at -0.5334 0 270)
			(size 0.7112 0.6096)
			(layers "B.Cu" "B.Mask" "B.Paste")
			(net "SG")
		)
		(zone
			(layer "B.Cu")
			(hatch none 0.5)
			(connect_pads
				(clearance 0)
			)
			(min_thickness 0.25)
			(keepout
				(tracks allowed)
				(vias not_allowed)
				(pads allowed)
				(copperpour not_allowed)
				(footprints allowed)
			)
			(placement
				(enabled no)
				(sheetname "")
			)
			(fill
				(thermal_gap 0.5)
				(thermal_bridge_width 0.5)
				(island_removal_mode 0)
			)
			(polygon
				(pts
					(xy 158.0388 -50.590196) (xy 157.4292 -50.590196) (xy 157.4292 -50.437796) (xy 158.0388 -50.437796)
				)
			)
		)
	)
)
